(kicad_pcb
	(version 20260206)
	(generator "pcbnew")
	(generator_version "10.0")
	(general
		(thickness 1.6)
		(legacy_teardrops no)
	)
	(paper "A4")
	(title_block
		(title "Wiwynn_Tioga_Pass_MB.brd")
		(comment 1 "Tioga Pass / footprints 235-240 of 4770")
	)
	(layers
		(0 "F.Cu" signal "TOP")
		(4 "In1.Cu" signal "L2GND")
		(6 "In2.Cu" signal "L3")
		(8 "In3.Cu" signal "L4GND")
		(10 "In4.Cu" signal "L5")
		(12 "In5.Cu" signal "L6GND")
		(14 "In6.Cu" signal "L7VCC")
		(16 "In7.Cu" signal "L8VCC")
		(18 "In8.Cu" signal "L9GND")
		(20 "In9.Cu" signal "L10")
		(22 "In10.Cu" signal "L11GND")
		(24 "In11.Cu" signal "L12")
		(26 "In12.Cu" signal "L13GND")
		(2 "B.Cu" signal "BOTTOM")
		(9 "F.Adhes" user "F.Adhesive")
		(11 "B.Adhes" user "B.Adhesive")
		(13 "F.Paste" user "Package Geometry/Pastemask Top")
		(15 "B.Paste" user "Package Geometry/Pastemask Bottom")
		(5 "F.SilkS" user "Ref Des/Silkscreen Top")
		(7 "B.SilkS" user "Ref Des/Silkscreen Bottom")
		(1 "F.Mask" user "Board Geometry/Soldermask Top")
		(3 "B.Mask" user "Board Geometry/Soldermask Bottom")
		(17 "Dwgs.User" user "User.Drawings")
		(19 "Cmts.User" user "User.Comments")
		(21 "Eco1.User" user "User.Eco1")
		(23 "Eco2.User" user "User.Eco2")
		(25 "Edge.Cuts" user "Board Geometry/Outline")
		(27 "Margin" user)
		(31 "F.CrtYd" user "Package Geometry/Place Bound Top")
		(29 "B.CrtYd" user "Package Geometry/Place Bound Bottom")
		(35 "F.Fab" user "Ref Des/Assembly Top")
		(33 "B.Fab" user "Ref Des/Assembly Bottom")
	)
	(footprint ""
		(layer "F.Cu")
		(at 375.92 -88.2015)
		(property "Reference" "R7C16"
			(at 0 0 0)
			(layer "F.SilkS")
			(hide yes)
			(effects
				(font
					(size 1.27 1.27)
				)
			)
		)
		(property "Value" ""
			(at 0 0 0)
			(layer "F.Fab")
			(effects
				(font
					(size 1.27 1.27)
				)
			)
		)
		(duplicate_pad_numbers_are_jumpers no)
		(fp_poly
			(pts
				(xy -0.2794 -0.1016) (xy 0.2794 -0.1016) (xy 0.2794 0.9906) (xy -0.2794 0.9906)
			)
			(stroke
				(width 0)
				(type default)
			)
			(fill no)
			(layer "F.CrtYd")
		)
		(fp_line
			(start -0.2794 -0.1016)
			(end -0.2794 0.9906)
			(stroke
				(width 0.1)
				(type default)
			)
			(layer "F.Fab")
		)
		(fp_line
			(start -0.2794 0.9906)
			(end 0.2794 0.9906)
			(stroke
				(width 0.1)
				(type default)
			)
			(layer "F.Fab")
		)
		(fp_line
			(start 0.2794 -0.1016)
			(end -0.2794 -0.1016)
			(stroke
				(width 0.1)
				(type default)
			)
			(layer "F.Fab")
		)
		(fp_line
			(start 0.2794 0.9906)
			(end 0.2794 -0.1016)
			(stroke
				(width 0.1)
				(type default)
			)
			(layer "F.Fab")
		)
		(pad "1" smd rect
			(at 0 0)
			(size 0.508 0.508)
			(layers "F.Cu" "F.Mask" "F.Paste")
			(net "SPI_PCH_CS0_R_N")
		)
		(pad "2" smd rect
			(at 0 0.889)
			(size 0.508 0.508)
			(layers "F.Cu" "F.Mask" "F.Paste")
			(net "SPI_PCH_CS0_N")
		)
		(zone
			(layer "F.Cu")
			(hatch none 0.5)
			(connect_pads
				(clearance 0)
			)
			(min_thickness 0.25)
			(keepout
				(tracks allowed)
				(vias not_allowed)
				(pads allowed)
				(copperpour not_allowed)
				(footprints allowed)
			)
			(placement
				(enabled no)
				(sheetname "")
			)
			(fill
				(thermal_gap 0.5)
				(thermal_bridge_width 0.5)
				(island_removal_mode 0)
			)
			(polygon
				(pts
					(xy 375.666 -87.9475) (xy 376.174 -87.9475) (xy 376.174 -87.5665) (xy 375.666 -87.5665)
				)
			)
		)
		(zone
			(layer "F.Cu")
			(hatch none 0.5)
			(connect_pads
				(clearance 0)
			)
			(min_thickness 0.25)
			(keepout
				(tracks not_allowed)
				(vias allowed)
				(pads allowed)
				(copperpour not_allowed)
				(footprints allowed)
			)
			(placement
				(enabled no)
				(sheetname "")
			)
			(fill
				(thermal_gap 0.5)
				(thermal_bridge_width 0.5)
				(island_removal_mode 0)
			)
			(polygon
				(pts
					(xy 375.666 -87.5665) (xy 376.174 -87.5665) (xy 376.174 -87.9475) (xy 375.666 -87.9475)
				)
			)
		)
	)
	(footprint ""
		(layer "F.Cu")
		(at 446.532 -12.954 90)
		(property "Reference" "U25W9"
			(at -0.14986 2.621788 90)
			(unlocked yes)
			(layer "F.SilkS")
			(effects
				(font
					(size 1.27 0.964946)
					(thickness 0.000001)
				)
				(justify left)
			)
		)
		(property "Value" ""
			(at 0 0 90)
			(layer "F.Fab")
			(effects
				(font
					(size 1.27 1.27)
				)
			)
		)
		(duplicate_pad_numbers_are_jumpers no)
		(fp_circle
			(center -0.4699 -0.8382)
			(end -0.4699 -0.7112)
			(stroke
				(width 0.254)
				(type default)
			)
			(fill no)
			(layer "F.SilkS")
		)
		(fp_poly
			(pts
				(xy 0.21463 -0.450088) (xy 1.56337 -0.450088) (xy 1.56337 1.75006) (xy 0.21463 1.75006)
			)
			(stroke
				(width 0)
				(type default)
			)
			(fill no)
			(layer "F.CrtYd")
		)
		(fp_line
			(start 1.56337 -0.450088)
			(end 1.56337 1.75006)
			(stroke
				(width 0.1)
				(type default)
			)
			(layer "F.Fab")
		)
		(fp_line
			(start 0.21463 -0.450088)
			(end 1.56337 -0.450088)
			(stroke
				(width 0.1)
				(type default)
			)
			(layer "F.Fab")
		)
		(fp_line
			(start 1.56337 1.75006)
			(end 0.21463 1.75006)
			(stroke
				(width 0.1)
				(type default)
			)
			(layer "F.Fab")
		)
		(fp_line
			(start 0.21463 1.75006)
			(end 0.21463 -0.450088)
			(stroke
				(width 0.1)
				(type default)
			)
			(layer "F.Fab")
		)
		(fp_circle
			(center -0.4699 -0.8382)
			(end -0.4699 -0.7112)
			(stroke
				(width 0.254)
				(type default)
			)
			(fill no)
			(layer "F.Fab")
		)
		(pad "1" smd rect
			(at 0 0 90)
			(size 1.016 0.381)
			(layers "F.Cu" "F.Mask" "F.Paste")
			(net "Net_6489")
		)
		(pad "2" smd rect
			(at 0 0.649986 90)
			(size 1.016 0.381)
			(layers "F.Cu" "F.Mask" "F.Paste")
			(net "PWRGD_DSW_PWROK")
		)
		(pad "3" smd rect
			(at 0 1.299972 90)
			(size 1.016 0.381)
			(layers "F.Cu" "F.Mask" "F.Paste")
			(net "GND")
		)
		(pad "4" smd rect
			(at 1.778 1.299972 90)
			(size 1.016 0.381)
			(layers "F.Cu" "F.Mask" "F.Paste")
			(net "RST_BMC_SRST_N")
		)
		(pad "5" smd rect
			(at 1.778 0 90)
			(size 1.016 0.381)
			(layers "F.Cu" "F.Mask" "F.Paste")
			(net "P3V3_STBY")
		)
	)
	(footprint ""
		(layer "F.Cu")
		(at 435.49062 -131.3053 -90)
		(property "Reference" "EU8B1"
			(at 3.04419 3.01244 0)
			(unlocked yes)
			(layer "F.SilkS")
			(effects
				(font
					(size 0.7874 0.5842)
					(thickness 0.1524)
				)
				(justify left)
			)
		)
		(property "Value" ""
			(at 0 0 270)
			(layer "F.Fab")
			(effects
				(font
					(size 1.27 1.27)
				)
			)
		)
		(duplicate_pad_numbers_are_jumpers no)
		(fp_circle
			(center -0.702056 -0.595376)
			(end -0.702056 -0.722376)
			(stroke
				(width 0.254)
				(type default)
			)
			(fill no)
			(layer "F.SilkS")
		)
		(fp_rect
			(start 0.5842 1.549908)
			(end 1.4732 -0.050292)
			(stroke
				(width 0)
				(type default)
			)
			(fill yes)
			(layer "F.Paste")
		)
		(fp_poly
			(pts
				(xy -0.021336 1.799844) (xy 2.078736 1.799844) (xy 2.078736 -0.300228) (xy -0.021336 -0.300228)
			)
			(stroke
				(width 0)
				(type default)
			)
			(fill no)
			(layer "F.CrtYd")
		)
		(fp_line
			(start -0.021336 1.799844)
			(end -0.021336 -0.300228)
			(stroke
				(width 0.1)
				(type default)
			)
			(layer "F.Fab")
		)
		(fp_line
			(start 2.078736 1.799844)
			(end -0.021336 1.799844)
			(stroke
				(width 0.1)
				(type default)
			)
			(layer "F.Fab")
		)
		(fp_line
			(start -0.021336 -0.300228)
			(end 2.078736 -0.300228)
			(stroke
				(width 0.1)
				(type default)
			)
			(layer "F.Fab")
		)
		(fp_line
			(start 2.078736 -0.300228)
			(end 2.078736 1.799844)
			(stroke
				(width 0.1)
				(type default)
			)
			(layer "F.Fab")
		)
		(fp_circle
			(center -0.702056 -0.595376)
			(end -0.702056 -0.722376)
			(stroke
				(width 0.254)
				(type default)
			)
			(fill no)
			(layer "F.Fab")
		)
		(pad "1" smd rect
			(at 0 0 270)
			(size 0.6604 0.3048)
			(layers "F.Cu" "F.Mask" "F.Paste")
			(net "P5V_STBY")
		)
		(pad "2" smd rect
			(at 0 0.499872 270)
			(size 0.6604 0.3048)
			(layers "F.Cu" "F.Mask" "F.Paste")
			(net "FM_CTNR_PS_ON")
		)
		(pad "3" smd rect
			(at 0 0.999744 270)
			(size 0.6604 0.3048)
			(layers "F.Cu" "F.Mask" "F.Paste")
			(net "P5V_STBY")
		)
		(pad "4" smd rect
			(at 0 1.499616 270)
			(size 0.6604 0.3048)
			(layers "F.Cu" "F.Mask" "F.Paste")
			(net "GND")
		)
		(pad "5" smd rect
			(at 2.0574 1.499616 270)
			(size 0.6604 0.3048)
			(layers "F.Cu" "F.Mask" "F.Paste")
			(net "P5V_STBY")
		)
		(pad "6" smd rect
			(at 2.0574 0.999744 270)
			(size 0.6604 0.3048)
			(layers "F.Cu" "F.Mask" "F.Paste")
			(net "P5V")
		)
		(pad "7" smd rect
			(at 2.0574 0.499872 270)
			(size 0.6604 0.3048)
			(layers "F.Cu" "F.Mask" "F.Paste")
			(net "P5V_SWITCH_G")
		)
		(pad "8" smd rect
			(at 2.0574 0 270)
			(size 0.6604 0.3048)
			(layers "F.Cu" "F.Mask" "F.Paste")
			(net "TP_SLG55021_P5V_8")
		)
		(pad "9" smd rect
			(at 1.0287 0.749808 270)
			(size 0.889 1.6002)
			(layers "F.Cu" "F.Mask" "F.Paste")
			(net "GND")
		)
	)
	(footprint ""
		(layer "F.Cu")
		(at 378.218192 -54.643528 90)
		(property "Reference" "C8E18"
			(at 0 0 90)
			(layer "F.SilkS")
			(hide yes)
			(effects
				(font
					(size 1.27 1.27)
				)
			)
		)
		(property "Value" ""
			(at 0 0 90)
			(layer "F.Fab")
			(effects
				(font
					(size 1.27 1.27)
				)
			)
		)
		(duplicate_pad_numbers_are_jumpers no)
		(fp_poly
			(pts
				(xy 0.3048 -0.1016) (xy 0.3048 0.9906) (xy -0.3048 0.9906) (xy -0.3048 -0.1016)
			)
			(stroke
				(width 0)
				(type default)
			)
			(fill no)
			(layer "F.CrtYd")
		)
		(fp_line
			(start 0.3048 -0.1016)
			(end -0.3048 -0.1016)
			(stroke
				(width 0.1)
				(type default)
			)
			(layer "F.Fab")
		)
		(fp_line
			(start -0.3048 -0.1016)
			(end -0.3048 0.9906)
			(stroke
				(width 0.1)
				(type default)
			)
			(layer "F.Fab")
		)
		(fp_line
			(start 0.3048 0.9906)
			(end 0.3048 -0.1016)
			(stroke
				(width 0.1)
				(type default)
			)
			(layer "F.Fab")
		)
		(fp_line
			(start -0.3048 0.9906)
			(end 0.3048 0.9906)
			(stroke
				(width 0.1)
				(type default)
			)
			(layer "F.Fab")
		)
		(pad "1" smd rect
			(at 0 0 90)
			(size 0.508 0.508)
			(layers "F.Cu" "F.Mask" "F.Paste")
			(net "P3V3_STBY")
		)
		(pad "2" smd rect
			(at 0 0.889 90)
			(size 0.508 0.508)
			(layers "F.Cu" "F.Mask" "F.Paste")
			(net "GND")
		)
		(zone
			(layer "F.Cu")
			(hatch none 0.5)
			(connect_pads
				(clearance 0)
			)
			(min_thickness 0.25)
			(keepout
				(tracks allowed)
				(vias not_allowed)
				(pads allowed)
				(copperpour not_allowed)
				(footprints allowed)
			)
			(placement
				(enabled no)
				(sheetname "")
			)
			(fill
				(thermal_gap 0.5)
				(thermal_bridge_width 0.5)
				(island_removal_mode 0)
			)
			(polygon
				(pts
					(xy 378.472192 -54.389528) (xy 378.472192 -54.897528) (xy 378.853192 -54.897528) (xy 378.853192 -54.389528)
				)
			)
		)
		(zone
			(layer "F.Cu")
			(hatch none 0.5)
			(connect_pads
				(clearance 0)
			)
			(min_thickness 0.25)
			(keepout
				(tracks not_allowed)
				(vias allowed)
				(pads allowed)
				(copperpour not_allowed)
				(footprints allowed)
			)
			(placement
				(enabled no)
				(sheetname "")
			)
			(fill
				(thermal_gap 0.5)
				(thermal_bridge_width 0.5)
				(island_removal_mode 0)
			)
			(polygon
				(pts
					(xy 378.853192 -54.389528) (xy 378.853192 -54.897528) (xy 378.472192 -54.897528) (xy 378.472192 -54.389528)
				)
			)
		)
	)
	(footprint ""
		(layer "F.Cu")
		(at 248.8565 -12.954 -90)
		(property "Reference" "C5G2"
			(at 1.848866 0.752348 270)
			(unlocked yes)
			(layer "F.SilkS")
			(effects
				(font
					(size 1.27 0.9652)
					(thickness 0.1524)
				)
			)
		)
		(property "Value" ""
			(at 0 0 270)
			(layer "F.Fab")
			(effects
				(font
					(size 1.27 1.27)
				)
			)
		)
		(duplicate_pad_numbers_are_jumpers no)
		(fp_rect
			(start -0.500126 1.598422)
			(end 0.500126 -0.201422)
			(stroke
				(width 0)
				(type default)
			)
			(fill no)
			(layer "F.CrtYd")
		)
		(fp_line
			(start -0.500126 1.598422)
			(end -0.500126 -0.201422)
			(stroke
				(width 0.1)
				(type default)
			)
			(layer "F.Fab")
		)
		(fp_line
			(start 0.500126 1.598422)
			(end -0.500126 1.598422)
			(stroke
				(width 0.1)
				(type default)
			)
			(layer "F.Fab")
		)
		(fp_line
			(start -0.500126 -0.201422)
			(end 0.500126 -0.201422)
			(stroke
				(width 0.1)
				(type default)
			)
			(layer "F.Fab")
		)
		(fp_line
			(start 0.500126 -0.201422)
			(end 0.500126 1.598422)
			(stroke
				(width 0.1)
				(type default)
			)
			(layer "F.Fab")
		)
		(pad "1" smd rect
			(at 0 0 180)
			(size 0.889 0.9906)
			(layers "F.Cu" "F.Mask" "F.Paste")
			(net "PVDDQ_ABC")
		)
		(pad "2" smd rect
			(at 0 1.397 180)
			(size 0.889 0.9906)
			(layers "F.Cu" "F.Mask" "F.Paste")
			(net "GND")
		)
		(zone
			(layer "F.Cu")
			(hatch none 0.5)
			(connect_pads
				(clearance 0)
			)
			(min_thickness 0.25)
			(keepout
				(tracks not_allowed)
				(vias allowed)
				(pads allowed)
				(copperpour not_allowed)
				(footprints allowed)
			)
			(placement
				(enabled no)
				(sheetname "")
			)
			(fill
				(thermal_gap 0.5)
				(thermal_bridge_width 0.5)
				(island_removal_mode 0)
			)
			(polygon
				(pts
					(xy 247.904 -13.4493) (xy 247.904 -12.4587) (xy 248.412 -12.4587) (xy 248.412 -13.4493)
				)
			)
		)
		(zone
			(layer "F.Cu")
			(hatch none 0.5)
			(connect_pads
				(clearance 0)
			)
			(min_thickness 0.25)
			(keepout
				(tracks allowed)
				(vias not_allowed)
				(pads allowed)
				(copperpour not_allowed)
				(footprints allowed)
			)
			(placement
				(enabled no)
				(sheetname "")
			)
			(fill
				(thermal_gap 0.5)
				(thermal_bridge_width 0.5)
				(island_removal_mode 0)
			)
			(polygon
				(pts
					(xy 247.904 -13.4493) (xy 247.904 -12.4587) (xy 248.412 -12.4587) (xy 248.412 -13.4493)
				)
			)
		)
	)
	(footprint ""
		(layer "F.Cu")
		(at 418.7952 -91.7829 -90)
		(property "Reference" "C8C15"
			(at 0 0 270)
			(layer "F.SilkS")
			(hide yes)
			(effects
				(font
					(size 1.27 1.27)
				)
			)
		)
		(property "Value" ""
			(at 0 0 270)
			(layer "F.Fab")
			(effects
				(font
					(size 1.27 1.27)
				)
			)
		)
		(duplicate_pad_numbers_are_jumpers no)
		(fp_poly
			(pts
				(xy 0.3048 -0.1016) (xy 0.3048 0.9906) (xy -0.3048 0.9906) (xy -0.3048 -0.1016)
			)
			(stroke
				(width 0)
				(type default)
			)
			(fill no)
			(layer "F.CrtYd")
		)
		(fp_line
			(start -0.3048 0.9906)
			(end 0.3048 0.9906)
			(stroke
				(width 0.1)
				(type default)
			)
			(layer "F.Fab")
		)
		(fp_line
			(start 0.3048 0.9906)
			(end 0.3048 -0.1016)
			(stroke
				(width 0.1)
				(type default)
			)
			(layer "F.Fab")
		)
		(fp_line
			(start -0.3048 -0.1016)
			(end -0.3048 0.9906)
			(stroke
				(width 0.1)
				(type default)
			)
			(layer "F.Fab")
		)
		(fp_line
			(start 0.3048 -0.1016)
			(end -0.3048 -0.1016)
			(stroke
				(width 0.1)
				(type default)
			)
			(layer "F.Fab")
		)
		(pad "1" smd rect
			(at 0 0 270)
			(size 0.508 0.508)
			(layers "F.Cu" "F.Mask" "F.Paste")
			(net "KR_P0_OCP_RX_DP")
		)
		(pad "2" smd rect
			(at 0 0.889 270)
			(size 0.508 0.508)
			(layers "F.Cu" "F.Mask" "F.Paste")
			(net "KR_P0_OCP_RX_C_DP")
		)
		(zone
			(layer "F.Cu")
			(hatch none 0.5)
			(connect_pads
				(clearance 0)
			)
			(min_thickness 0.25)
			(keepout
				(tracks not_allowed)
				(vias allowed)
				(pads allowed)
				(copperpour not_allowed)
				(footprints allowed)
			)
			(placement
				(enabled no)
				(sheetname "")
			)
			(fill
				(thermal_gap 0.5)
				(thermal_bridge_width 0.5)
				(island_removal_mode 0)
			)
			(polygon
				(pts
					(xy 418.1602 -92.0369) (xy 418.1602 -91.5289) (xy 418.5412 -91.5289) (xy 418.5412 -92.0369)
				)
			)
		)
		(zone
			(layer "F.Cu")
			(hatch none 0.5)
			(connect_pads
				(clearance 0)
			)
			(min_thickness 0.25)
			(keepout
				(tracks allowed)
				(vias not_allowed)
				(pads allowed)
				(copperpour not_allowed)
				(footprints allowed)
			)
			(placement
				(enabled no)
				(sheetname "")
			)
			(fill
				(thermal_gap 0.5)
				(thermal_bridge_width 0.5)
				(island_removal_mode 0)
			)
			(polygon
				(pts
					(xy 418.5412 -92.0369) (xy 418.5412 -91.5289) (xy 418.1602 -91.5289) (xy 418.1602 -92.0369)
				)
			)
		)
	)
)
